# T6G (Grand Teton) — schematic netlist excerpt (pin names and nets, part order shuffled) for the footprints in the layout excerpt that follows; sources: Cadence DE-HDL packaged netlist, KiCad conversion of 04192023_DAF0TMB3IC0_F0TG_MB_C_brd_V02_OCP.brd

C6671  Q_CAP_DIFFBUS  DIFF BUS_0.22UF 6.3V 20% X6S  pkg C0201  page 330 : \1\ = P5E_CPU1_P1_TX_BUF_C_DP<5> ; \2\ = P5E_CPU1_P1_TX_BUF_DP<5>
PC604_1  Q_CAP  22UF 4V 20% X6S  pkg C0805  page 198 : A = PVDDCR_SOC_P0 ; B = GND
R6766  Q_RES  1K 1% CHIP  pkg 0201LF  page 184 : A = P1V8_CPU0_RT_1D ; B = SMB_RT_CPU0_P3_R_SDA

Q108  MOSFET_NCH_DUAL  PJT138K IC  pkg SOT363XD  page 126
  S1  = GND
  G1  = GPU_FPGA_EROT_FATALERR_N
  D2  = GPU_FPGA_EROT_FATALERR_ISO_N
  S2  = GND
  G2  = GPU_FPGA_EROT_FATALERR
  D1  = GPU_FPGA_EROT_FATALERR

(kicad_pcb
	(version 20260206)
	(generator "pcbnew")
	(generator_version "10.0")
	(general
		(thickness 1.6)
		(legacy_teardrops no)
	)
	(paper "A4")
	(title_block
		(title "04192023_DAF0TMB3IC0_F0TG_MB_C_brd_V02_OCP.brd")
		(comment 1 "Grand Teton / footprints 5805-5808 of 8354")
	)
	(layers
		(0 "F.Cu" signal "TOP")
		(4 "In1.Cu" signal "GND")
		(6 "In2.Cu" signal "IN1")
		(8 "In3.Cu" signal "GND1")
		(10 "In4.Cu" signal "IN2")
		(12 "In5.Cu" signal "GND2")
		(14 "In6.Cu" signal "IN3")
		(16 "In7.Cu" signal "GND3")
		(18 "In8.Cu" signal "VCC")
		(20 "In9.Cu" signal "VCC1")
		(22 "In10.Cu" signal "GND4")
		(24 "In11.Cu" signal "IN4")
		(26 "In12.Cu" signal "GND5")
		(28 "In13.Cu" signal "IN5")
		(30 "In14.Cu" signal "GND6")
		(32 "In15.Cu" signal "IN6")
		(34 "In16.Cu" signal "GND7")
		(2 "B.Cu" signal "BOTTOM")
		(9 "F.Adhes" user "F.Adhesive")
		(11 "B.Adhes" user "B.Adhesive")
		(13 "F.Paste" user "Package Geometry/Pastemask Top")
		(15 "B.Paste" user "Package Geometry/Pastemask Bottom")
		(5 "F.SilkS" user "Ref Des/Silkscreen Top")
		(7 "B.SilkS" user "Ref Des/Silkscreen Bottom")
		(1 "F.Mask" user "Board Geometry/Soldermask Top")
		(3 "B.Mask" user "Board Geometry/Soldermask Bottom")
		(17 "Dwgs.User" user "User.Drawings")
		(19 "Cmts.User" user "User.Comments")
		(21 "Eco1.User" user "User.Eco1")
		(23 "Eco2.User" user "User.Eco2")
		(25 "Edge.Cuts" user "Board Geometry/Outline")
		(27 "Margin" user)
		(31 "F.CrtYd" user "Package Geometry/Place Bound Top")
		(29 "B.CrtYd" user "Package Geometry/Place Bound Bottom")
		(35 "F.Fab" user "Ref Des/Assembly Top")
		(33 "B.Fab" user "Ref Des/Assembly Bottom")
	)
	(footprint ""
		(layer "B.Cu")
		(at 394.335 -185.63336 90)
		(property "Reference" "PC604_1"
			(at 0 0 90)
			(layer "B.SilkS")
			(hide yes)
			(effects
				(font
					(size 1.27 1.27)
				)
				(justify mirror)
			)
		)
		(property "Value" ""
			(at 0 0 90)
			(layer "B.Fab")
			(effects
				(font
					(size 1.27 1.27)
				)
				(justify mirror)
			)
		)
		(duplicate_pad_numbers_are_jumpers no)
		(fp_line
			(start 1.524 -0.762)
			(end -1.524 -0.762)
			(stroke
				(width 0.1524)
				(type default)
			)
			(layer "B.SilkS")
		)
		(fp_line
			(start -1.524 -0.762)
			(end -1.524 0.762)
			(stroke
				(width 0.1524)
				(type default)
			)
			(layer "B.SilkS")
		)
		(fp_line
			(start 1.524 0.762)
			(end 1.524 -0.762)
			(stroke
				(width 0.1524)
				(type default)
			)
			(layer "B.SilkS")
		)
		(fp_line
			(start -1.524 0.762)
			(end 1.524 0.762)
			(stroke
				(width 0.1524)
				(type default)
			)
			(layer "B.SilkS")
		)
		(fp_line
			(start 1.1049 -0.724916)
			(end 1.1049 0.724916)
			(stroke
				(width 0.1)
				(type default)
			)
			(layer "B.Fab")
		)
		(fp_line
			(start -1.1049 -0.724916)
			(end 1.1049 -0.724916)
			(stroke
				(width 0.1)
				(type default)
			)
			(layer "B.Fab")
		)
		(fp_line
			(start 1.1049 0.724916)
			(end -1.1049 0.724916)
			(stroke
				(width 0.1)
				(type default)
			)
			(layer "B.Fab")
		)
		(fp_line
			(start -1.1049 0.724916)
			(end -1.1049 -0.724916)
			(stroke
				(width 0.1)
				(type default)
			)
			(layer "B.Fab")
		)
		(pad "1" smd rect
			(at 0.889 0 90)
			(size 1.016 1.27)
			(layers "B.Cu" "B.Mask" "B.Paste")
			(net "PVDDCR_SOC_P0")
		)
		(pad "2" smd rect
			(at -0.889 0 90)
			(size 1.016 1.27)
			(layers "B.Cu" "B.Mask" "B.Paste")
			(net "GND")
		)
	)
	(footprint ""
		(layer "B.Cu")
		(at 113.919 -417.576)
		(property "Reference" "Q108"
			(at 0.311658 -2.625598 0)
			(unlocked yes)
			(layer "B.SilkS")
			(effects
				(font
					(size 0.7874 0.5842)
					(thickness 0.1524)
				)
				(justify left mirror)
			)
		)
		(property "Value" ""
			(at 0 0 0)
			(layer "B.Fab")
			(effects
				(font
					(size 1.27 1.27)
				)
				(justify mirror)
			)
		)
		(duplicate_pad_numbers_are_jumpers no)
		(fp_line
			(start -1.332738 -1.100074)
			(end -1.332738 1.100074)
			(stroke
				(width 0.1524)
				(type default)
			)
			(layer "B.SilkS")
		)
		(fp_line
			(start -1.332738 1.100074)
			(end 1.332738 1.100074)
			(stroke
				(width 0.1524)
				(type default)
			)
			(layer "B.SilkS")
		)
		(fp_line
			(start -0.4826 -1.100074)
			(end -1.332738 -1.100074)
			(stroke
				(width 0.1524)
				(type default)
			)
			(layer "B.SilkS")
		)
		(fp_line
			(start 0 -0.541274)
			(end -0.4826 -1.100074)
			(stroke
				(width 0.1524)
				(type default)
			)
			(layer "B.SilkS")
		)
		(fp_line
			(start 0.4826 -1.100074)
			(end 0 -0.541274)
			(stroke
				(width 0.1524)
				(type default)
			)
			(layer "B.SilkS")
		)
		(fp_line
			(start 1.332738 -1.100074)
			(end 0.4826 -1.100074)
			(stroke
				(width 0.1524)
				(type default)
			)
			(layer "B.SilkS")
		)
		(fp_line
			(start 1.332738 1.100074)
			(end 1.332738 -1.100074)
			(stroke
				(width 0.1524)
				(type default)
			)
			(layer "B.SilkS")
		)
		(fp_poly
			(pts
				(xy 0.914146 -1.289558) (xy 1.257554 -1.99517) (xy 0.555752 -1.987804)
			)
			(stroke
				(width 0)
				(type default)
			)
			(fill yes)
			(layer "B.SilkS")
		)
		(fp_line
			(start -0.674878 -1.100074)
			(end -0.674878 1.100074)
			(stroke
				(width 0.1)
				(type default)
			)
			(layer "B.Fab")
		)
		(fp_line
			(start -0.674878 1.100074)
			(end 0.674878 1.100074)
			(stroke
				(width 0.1)
				(type default)
			)
			(layer "B.Fab")
		)
		(fp_line
			(start 0.674878 -1.100074)
			(end -0.674878 -1.100074)
			(stroke
				(width 0.1)
				(type default)
			)
			(layer "B.Fab")
		)
		(fp_line
			(start 0.674878 1.100074)
			(end 0.674878 -1.100074)
			(stroke
				(width 0.1)
				(type default)
			)
			(layer "B.Fab")
		)
		(fp_poly
			(pts
				(xy 2.2352 -0.298958) (xy 2.2352 -1.001014) (xy 1.533144 -0.649986)
			)
			(stroke
				(width 0)
				(type default)
			)
			(fill yes)
			(layer "B.Fab")
		)
		(pad "1" smd rect
			(at 0.94996 -0.649986 90)
			(size 0.4318 0.508)
			(layers "B.Cu" "B.Mask" "B.Paste")
			(net "GND")
		)
		(pad "2" smd rect
			(at 0.94996 0 90)
			(size 0.4318 0.508)
			(layers "B.Cu" "B.Mask" "B.Paste")
			(net "GPU_FPGA_EROT_FATALERR_N")
		)
		(pad "3" smd rect
			(at 0.94996 0.649986 90)
			(size 0.4318 0.508)
			(layers "B.Cu" "B.Mask" "B.Paste")
			(net "GPU_FPGA_EROT_FATALERR_ISO_N")
		)
		(pad "4" smd rect
			(at -0.94996 0.649986 90)
			(size 0.4318 0.508)
			(layers "B.Cu" "B.Mask" "B.Paste")
			(net "GND")
		)
		(pad "5" smd rect
			(at -0.94996 0 90)
			(size 0.4318 0.508)
			(layers "B.Cu" "B.Mask" "B.Paste")
			(net "GPU_FPGA_EROT_FATALERR")
		)
		(pad "6" smd rect
			(at -0.94996 -0.649986 90)
			(size 0.4318 0.508)
			(layers "B.Cu" "B.Mask" "B.Paste")
			(net "GPU_FPGA_EROT_FATALERR")
		)
	)
	(footprint ""
		(layer "B.Cu")
		(at 231.648 -337.439 90)
		(property "Reference" "R6766"
			(at 0 0 90)
			(layer "B.SilkS")
			(hide yes)
			(effects
				(font
					(size 1.27 1.27)
				)
				(justify mirror)
			)
		)
		(property "Value" ""
			(at 0 0 90)
			(layer "B.Fab")
			(effects
				(font
					(size 1.27 1.27)
				)
				(justify mirror)
			)
		)
		(duplicate_pad_numbers_are_jumpers no)
		(fp_line
			(start 0.32512 -0.175006)
			(end -0.32512 -0.175006)
			(stroke
				(width 0.1)
				(type default)
			)
			(layer "B.Fab")
		)
		(fp_line
			(start -0.32512 -0.175006)
			(end -0.32512 0.175006)
			(stroke
				(width 0.1)
				(type default)
			)
			(layer "B.Fab")
		)
		(fp_line
			(start 0.32512 0.175006)
			(end 0.32512 -0.175006)
			(stroke
				(width 0.1)
				(type default)
			)
			(layer "B.Fab")
		)
		(fp_line
			(start -0.32512 0.175006)
			(end 0.32512 0.175006)
			(stroke
				(width 0.1)
				(type default)
			)
			(layer "B.Fab")
		)
		(pad "1" smd rect
			(at 0.2667 0 270)
			(size 0.3048 0.381)
			(layers "B.Cu" "B.Mask" "B.Paste")
			(net "P1V8_CPU0_RT_1D")
		)
		(pad "2" smd rect
			(at -0.2667 0 90)
			(size 0.3048 0.381)
			(layers "B.Cu" "B.Mask" "B.Paste")
			(net "SMB_RT_CPU0_P3_R_SDA")
		)
	)
	(footprint ""
		(layer "B.Cu")
		(at 65.530984 -408.517344 90)
		(property "Reference" "C6671"
			(at 0 0 90)
			(layer "B.SilkS")
			(hide yes)
			(effects
				(font
					(size 1.27 1.27)
				)
				(justify mirror)
			)
		)
		(property "Value" ""
			(at 0 0 90)
			(layer "B.Fab")
			(effects
				(font
					(size 1.27 1.27)
				)
				(justify mirror)
			)
		)
		(duplicate_pad_numbers_are_jumpers no)
		(fp_line
			(start 0.299974 -0.150114)
			(end -0.299974 -0.150114)
			(stroke
				(width 0.1)
				(type default)
			)
			(layer "B.Fab")
		)
		(fp_line
			(start -0.299974 -0.150114)
			(end -0.299974 0.150114)
			(stroke
				(width 0.1)
				(type default)
			)
			(layer "B.Fab")
		)
		(fp_line
			(start 0.299974 0.150114)
			(end 0.299974 -0.150114)
			(stroke
				(width 0.1)
				(type default)
			)
			(layer "B.Fab")
		)
		(fp_line
			(start -0.299974 0.150114)
			(end 0.299974 0.150114)
			(stroke
				(width 0.1)
				(type default)
			)
			(layer "B.Fab")
		)
		(pad "1" smd rect
			(at 0.2667 0 270)
			(size 0.3048 0.381)
			(layers "B.Cu" "B.Mask" "B.Paste")
			(net "P5E_CPU1_P1_TX_BUF_C_DP<5>")
		)
		(pad "2" smd rect
			(at -0.2667 0 270)
			(size 0.3048 0.381)
			(layers "B.Cu" "B.Mask" "B.Paste")
			(net "P5E_CPU1_P1_TX_BUF_DP<5>")
		)
	)
)
